#ISCELL
  mstr_misc dns *
  *
#ISCELL
  mstr_symbols cad_note *
  *
#ISCELL
  mstr_symbols design_note *
  *
#ISCELL
  mstr_symbols intel_corp_bpage *
  *
#CELL
  mstr_analog tmp421 *
  page167_i1
#CELL
  mstr_discrete res *
  page167_i10
#ISCELL
  mstr_symbols gnd *
  page167_i12
#ISCELL
  mstr_symbols p3v3_stby *
  page167_i14
#ISCELL
  mstr_symbols gnd *
  page167_i15
#ISCELL
  mstr_standard offpage *
  page167_i16
#ISCELL
  mstr_standard offpage *
  page167_i17
#ISCELL
  mstr_symbols gnd *
  page167_i22
#ISCELL
  mstr_symbols p3v3_stby *
  page167_i23
#CELL
  mstr_discrete cap *
  page167_i24
#CELL
  mstr_discrete res *
  page167_i25
#CELL
  mstr_discrete res *
  page167_i26
#CELL
  mstr_discrete pnp *
  page167_i27
#ISCELL
  mstr_symbols p3v3_stby *
  page167_i29
#CELL
  mstr_discrete pnp *
  page167_i3
#CELL
  mstr_analog tmp421 *
  page167_i30
#CELL
  mstr_discrete res *
  page167_i34
#CELL
  mstr_discrete res *
  page167_i35
#CELL
  mstr_discrete res *
  page167_i38
#CELL
  dev_discrete cap_a *
  page167_i39
#CELL
  dev_discrete cap_a *
  page167_i41
#CELL
  dev_discrete cap_a *
  page167_i42
#ISCELL
  mstr_symbols gnd *
  page167_i45
#ISCELL
  mstr_symbols gnd *
  page167_i46
#ISCELL
  mstr_symbols gnd *
  page167_i47
#CELL
  mstr_memory at24c64 *
  page167_i49
#CELL
  mstr_discrete res *
  page167_i5
#CELL
  mstr_discrete res *
  page167_i50
#ISCELL
  mstr_symbols gnd *
  page167_i52
#ISCELL
  mstr_symbols gnd *
  page167_i55
#ISCELL
  mstr_symbols p3v3_stby *
  page167_i56
#ISCELL
  mstr_symbols p3v3_stby *
  page167_i57
#CELL
  mstr_discrete res *
  page167_i58
#CELL
  mstr_discrete res *
  page167_i6
#ISCELL
  mstr_standard offpage *
  page167_i60
#ISCELL
  mstr_standard offpage *
  page167_i61
#ISCELL
  mstr_standard offpage *
  page167_i62
#ISCELL
  mstr_standard offpage *
  page167_i63
#ISCELL
  mstr_standard offpage *
  page167_i64
#ISCELL
  mstr_standard offpage *
  page167_i65
#ISCELL
  mstr_standard offpage *
  page167_i67
#ISCELL
  mstr_standard offpage *
  page167_i69
#CELL
  mstr_discrete cap *
  page167_i7
#CELL
  mstr_discrete res *
  page167_i70
#ISCELL
  mstr_symbols p3v3_stby *
  page167_i71
#ISCELL
  mstr_symbols p3v3_stby *
  page167_i72
#ISCELL
  mstr_symbols p3v3_stby *
  page167_i73
#CELL
  mstr_discrete res *
  page167_i74
#CELL
  mstr_discrete res *
  page167_i75
#CELL
  mstr_discrete res *
  page167_i76
#CELL
  mstr_discrete res *
  page167_i77
#CELL
  mstr_discrete res *
  page167_i78
#CELL
  mstr_discrete res *
  page167_i79
#CELL
  mstr_discrete res *
  page167_i8
#CELL
  mstr_discrete res *
  page167_i80
#ISCELL
  mstr_symbols p3v3_stby *
  page167_i81
#ISCELL
  mstr_symbols p3v3_stby *
  page167_i82
#CELL
  mstr_discrete res *
  page167_i83
#CELL
  mstr_discrete res *
  page167_i84
#CELL
  mstr_discrete res *
  page167_i85
#ISCELL
  mstr_standard offpage *
  page167_i86
#ISCELL
  mstr_standard offpage *
  page167_i87
